(kicad_pcb
	(version 20241229)
	(generator "pcbnew")
	(generator_version "9.0")
	(general
		(thickness 1.552)
		(legacy_teardrops no)
	)
	(paper "A4")
	(title_block
		(date "2023-07-25")
		(rev "1.1.4")
		(comment 9 "footprints 120-123 of 379")
	)
	(layers
		(0 "F.Cu" signal)
		(4 "In1.Cu" signal)
		(6 "In2.Cu" signal)
		(8 "In3.Cu" signal)
		(10 "In4.Cu" signal)
		(12 "In5.Cu" signal)
		(14 "In6.Cu" signal)
		(2 "B.Cu" signal)
		(9 "F.Adhes" user "F.Adhesive")
		(11 "B.Adhes" user "B.Adhesive")
		(13 "F.Paste" user)
		(15 "B.Paste" user)
		(5 "F.SilkS" user "F.Silkscreen")
		(7 "B.SilkS" user "B.Silkscreen")
		(1 "F.Mask" user)
		(3 "B.Mask" user)
		(17 "Dwgs.User" user "User.Drawings")
		(19 "Cmts.User" user "User.Comments")
		(21 "Eco1.User" user "User.Eco1")
		(23 "Eco2.User" user "User.Eco2")
		(25 "Edge.Cuts" user)
		(27 "Margin" user)
		(31 "F.CrtYd" user "F.Courtyard")
		(29 "B.CrtYd" user "B.Courtyard")
		(35 "F.Fab" user)
		(33 "B.Fab" user)
	)
	(footprint "antmicro-footprints:L_Coilcraft-XEL4030"
		(layer "F.Cu")
		(at 142.48 59.29 -90)
		(property "Reference" "L2"
			(at -2.65 2.15 0)
			(layer "F.SilkS")
			(effects
				(font
					(size 0.65 0.65)
					(thickness 0.15)
				)
				(justify left bottom)
			)
		)
		(property "Value" "L_3u3_5.9A_XEL4030"
			(at 0 3.35 270)
			(layer "F.Fab")
			(hide yes)
			(effects
				(font
					(size 0.7 0.7)
					(thickness 0.15)
				)
				(justify left bottom)
			)
		)
		(property "Datasheet" "https://www.coilcraft.com/getmedia/8245f050-f190-4295-8c41-7c03d662ee3d/xel4030.pdf"
			(at 0 0 270)
			(layer "F.Fab")
			(hide yes)
			(effects
				(font
					(size 1.27 1.27)
					(thickness 0.15)
				)
			)
		)
		(property "Description" "Power Inductor (SMT), AEC-Q200, 3.3 µH, 6.6 A, Shielded, 5.9 A, XEL4030"
			(at 0 0 270)
			(layer "F.Fab")
			(hide yes)
			(effects
				(font
					(size 1.27 1.27)
					(thickness 0.15)
				)
			)
		)
		(property "Author" "Antmicro"
			(at 83.19 201.77 0)
			(layer "F.Fab")
			(hide yes)
			(effects
				(font
					(size 1 1)
					(thickness 0.15)
				)
			)
		)
		(property "IMax" "6.6 A"
			(at 83.19 201.77 0)
			(layer "F.Fab")
			(hide yes)
			(effects
				(font
					(size 1 1)
					(thickness 0.15)
				)
			)
		)
		(property "ISat" "5.9 A"
			(at 83.19 201.77 0)
			(layer "F.Fab")
			(hide yes)
			(effects
				(font
					(size 1 1)
					(thickness 0.15)
				)
			)
		)
		(property "License" "Apache-2.0"
			(at 83.19 201.77 0)
			(layer "F.Fab")
			(hide yes)
			(effects
				(font
					(size 1 1)
					(thickness 0.15)
				)
			)
		)
		(property "MPN" "XEL4030-332MEC"
			(at 83.19 201.77 0)
			(layer "F.Fab")
			(hide yes)
			(effects
				(font
					(size 1 1)
					(thickness 0.15)
				)
			)
		)
		(property "Manufacturer" "Coilcraft"
			(at 83.19 201.77 0)
			(layer "F.Fab")
			(hide yes)
			(effects
				(font
					(size 1 1)
					(thickness 0.15)
				)
			)
		)
		(property "Size" "4.0x4.0"
			(at 83.19 201.77 0)
			(layer "F.Fab")
			(hide yes)
			(effects
				(font
					(size 1 1)
					(thickness 0.15)
				)
			)
		)
		(property "Val" "3u3/6.6A"
			(at 83.19 201.77 0)
			(layer "F.Fab")
			(hide yes)
			(effects
				(font
					(size 1 1)
					(thickness 0.15)
				)
			)
		)
		(sheetname "/Power Supply/")
		(sheetfile "supply.kicad_sch")
		(attr smd)
		(fp_line
			(start -2.2 2.2)
			(end 2.2 2.2)
			(stroke
				(width 0.15)
				(type solid)
			)
			(layer "F.SilkS")
		)
		(fp_line
			(start -2.2 2.2)
			(end -2.2 -2.2)
			(stroke
				(width 0.15)
				(type solid)
			)
			(layer "F.SilkS")
		)
		(fp_line
			(start 2.2 2.2)
			(end 2.2 -2.2)
			(stroke
				(width 0.15)
				(type solid)
			)
			(layer "F.SilkS")
		)
		(fp_line
			(start -2.2 -2.2)
			(end 2.2 -2.2)
			(stroke
				(width 0.15)
				(type solid)
			)
			(layer "F.SilkS")
		)
		(fp_rect
			(start -2.4 -2.4)
			(end 2.4 2.4)
			(stroke
				(width 0.05)
				(type solid)
			)
			(fill no)
			(layer "F.CrtYd")
		)
		(fp_rect
			(start -2.15 -2.15)
			(end 2.15 2.15)
			(stroke
				(width 0.15)
				(type solid)
			)
			(fill no)
			(layer "F.Fab")
		)
		(fp_text user "${REFERENCE}"
			(at -2.4 6.55 270)
			(layer "F.Fab")
			(effects
				(font
					(size 0.7 0.7)
					(thickness 0.15)
				)
				(justify left bottom)
			)
		)
		(fp_text user "Author: Antmicro"
			(at -2.4 5.35 270)
			(layer "F.Fab")
			(effects
				(font
					(size 0.7 0.7)
					(thickness 0.15)
				)
				(justify left bottom)
			)
		)
		(fp_text user "License: Apache-2.0"
			(at -2.4 7.75 270)
			(layer "F.Fab")
			(effects
				(font
					(size 0.7 0.7)
					(thickness 0.15)
				)
				(justify left bottom)
			)
		)
		(pad "1" smd roundrect
			(at -1.185 0 270)
			(size 0.98 3.4)
			(layers "F.Cu" "F.Mask" "F.Paste")
			(roundrect_rratio 0.1)
			(net 277 "/Power Supply/1V5_SW")
			(pintype "passive")
		)
		(pad "2" smd roundrect
			(at 1.185 0 270)
			(size 0.98 3.4)
			(layers "F.Cu" "F.Mask" "F.Paste")
			(roundrect_rratio 0.1)
			(net 274 "/Power Supply/1V5_OUT")
			(pintype "passive")
		)
	)
	(footprint "antmicro-footprints:LED_0603_1608Metric_G"
		(layer "F.Cu")
		(at 127 109.65 -90)
		(descr "LED SMD 0603 Green")
		(tags "LED SMD 0603 Green")
		(property "Reference" "D5"
			(at -2.71 0.37 90)
			(layer "F.SilkS")
			(effects
				(font
					(size 0.65 0.65)
					(thickness 0.15)
				)
				(justify right top)
			)
		)
		(property "Value" "LED_G_0603_LTST-C190GKT"
			(at 0 1.6 90)
			(layer "F.Fab")
			(hide yes)
			(effects
				(font
					(size 0.7 0.7)
					(thickness 0.15)
				)
				(justify right top)
			)
		)
		(property "Datasheet" "https://media.digikey.com/pdf/Data%20Sheets/Lite-On%20PDFs/LTST-C190GKT.pdf"
			(at 0 0 90)
			(layer "F.Fab")
			(hide yes)
			(effects
				(font
					(size 1.27 1.27)
					(thickness 0.15)
				)
			)
		)
		(property "Description" "LED, Green, SMD, 0603, 20 mA, 2.1 V, 569 nm"
			(at 0 0 90)
			(layer "F.Fab")
			(hide yes)
			(effects
				(font
					(size 1.27 1.27)
					(thickness 0.15)
				)
			)
		)
		(property "Author" "Antmicro"
			(at 236.65 -17.35 0)
			(layer "F.Fab")
			(hide yes)
			(effects
				(font
					(size 1 1)
					(thickness 0.15)
				)
			)
		)
		(property "License" "Apache-2.0"
			(at 236.65 -17.35 0)
			(layer "F.Fab")
			(hide yes)
			(effects
				(font
					(size 1 1)
					(thickness 0.15)
				)
			)
		)
		(property "MPN" "LTST-C190GKT"
			(at 236.65 -17.35 0)
			(layer "F.Fab")
			(hide yes)
			(effects
				(font
					(size 1 1)
					(thickness 0.15)
				)
			)
		)
		(property "Manufacturer" "Lite-On"
			(at 236.65 -17.35 0)
			(layer "F.Fab")
			(hide yes)
			(effects
				(font
					(size 1 1)
					(thickness 0.15)
				)
			)
		)
		(property "Color" "Green"
			(at 0 0 270)
			(unlocked yes)
			(layer "F.Fab")
			(hide yes)
			(effects
				(font
					(size 1 1)
					(thickness 0.15)
				)
			)
		)
		(sheetname "/FPGA/")
		(sheetfile "fpga.kicad_sch")
		(attr smd)
		(fp_line
			(start 0.22 0.35)
			(end -0.22 0.35)
			(stroke
				(width 0.15)
				(type solid)
			)
			(layer "F.SilkS")
		)
		(fp_line
			(start -0.094672 0.201008)
			(end -0.094672 -0.198992)
			(stroke
				(width 0.1)
				(type solid)
			)
			(layer "F.SilkS")
		)
		(fp_line
			(start 0.105328 0.201008)
			(end -0.094672 0.001008)
			(stroke
				(width 0.1)
				(type solid)
			)
			(layer "F.SilkS")
		)
		(fp_line
			(start 0.105328 0.201008)
			(end 0.105328 -0.198992)
			(stroke
				(width 0.1)
				(type solid)
			)
			(layer "F.SilkS")
		)
		(fp_line
			(start -0.094672 0.001008)
			(end -0.24 0.001008)
			(stroke
				(width 0.1)
				(type solid)
			)
			(layer "F.SilkS")
		)
		(fp_line
			(start -0.094672 0.001008)
			(end 0.105328 -0.198992)
			(stroke
				(width 0.1)
				(type solid)
			)
			(layer "F.SilkS")
		)
		(fp_line
			(start 0.105328 0.001008)
			(end 0.24 0.001)
			(stroke
				(width 0.1)
				(type solid)
			)
			(layer "F.SilkS")
		)
		(fp_line
			(start -1.18 -0.319)
			(end -1.18 0.321)
			(stroke
				(width 0.15)
				(type solid)
			)
			(layer "F.SilkS")
		)
		(fp_line
			(start 0.22 -0.35)
			(end -0.22 -0.35)
			(stroke
				(width 0.15)
				(type solid)
			)
			(layer "F.SilkS")
		)
		(fp_rect
			(start 1.25 0.65)
			(end -1.25 -0.65)
			(stroke
				(width 0.05)
				(type solid)
			)
			(fill no)
			(layer "F.CrtYd")
		)
		(fp_line
			(start -0.199 0.2)
			(end -0.199 0.1)
			(stroke
				(width 0.15)
				(type solid)
			)
			(layer "F.Fab")
		)
		(fp_line
			(start 0.201 0.2)
			(end 0.201 0)
			(stroke
				(width 0.15)
				(type solid)
			)
			(layer "F.Fab")
		)
		(fp_line
			(start -0.199 0)
			(end -0.597 0)
			(stroke
				(width 0.15)
				(type solid)
			)
			(layer "F.Fab")
		)
		(fp_line
			(start -0.101 0)
			(end 0.201 0.2)
			(stroke
				(width 0.15)
				(type solid)
			)
			(layer "F.Fab")
		)
		(fp_line
			(start 0.201 0)
			(end 0.201 -0.202)
			(stroke
				(width 0.15)
				(type solid)
			)
			(layer "F.Fab")
		)
		(fp_line
			(start 0.599 0)
			(end 0.201 0)
			(stroke
				(width 0.15)
				(type solid)
			)
			(layer "F.Fab")
		)
		(fp_line
			(start -0.199 -0.202)
			(end -0.199 0.1)
			(stroke
				(width 0.15)
				(type solid)
			)
			(layer "F.Fab")
		)
		(fp_line
			(start 0.201 -0.202)
			(end -0.101 0)
			(stroke
				(width 0.15)
				(type solid)
			)
			(layer "F.Fab")
		)
		(fp_rect
			(start 0.848 0.4)
			(end -0.85 -0.402)
			(stroke
				(width 0.15)
				(type solid)
			)
			(fill no)
			(layer "F.Fab")
		)
		(fp_text user "Author: Antmicro"
			(at -1.4224 4.799 90)
			(layer "F.Fab")
			(effects
				(font
					(size 0.7 0.7)
					(thickness 0.15)
				)
				(justify right top)
			)
		)
		(fp_text user "${REFERENCE}"
			(at -1.4224 5.999 90)
			(layer "F.Fab")
			(effects
				(font
					(size 0.7 0.7)
					(thickness 0.15)
				)
				(justify right top)
			)
		)
		(fp_text user "License: Apache-2.0"
			(at -1.4224 3.599 90)
			(layer "F.Fab")
			(effects
				(font
					(size 0.7 0.7)
					(thickness 0.15)
				)
				(justify right top)
			)
		)
		(pad "1" smd roundrect
			(at -0.7 0 90)
			(size 0.8 1)
			(layers "F.Cu" "F.Mask" "F.Paste")
			(roundrect_rratio 0.2)
			(net 66 "Net-(D5-C)")
			(pinfunction "C")
			(pintype "passive")
		)
		(pad "2" smd roundrect
			(at 0.7 0 90)
			(size 0.8 1)
			(layers "F.Cu" "F.Mask" "F.Paste")
			(roundrect_rratio 0.2)
			(net 67 "Net-(D5-A)")
			(pinfunction "A")
			(pintype "passive")
		)
	)
	(footprint "antmicro-footprints:R_0603_1608Metric"
		(layer "F.Cu")
		(at 158.53 88.65 90)
		(descr "Resistor SMD 0603")
		(tags "resistor SMD 0603")
		(property "Reference" "R105"
			(at 1.21 -1.1 90)
			(layer "F.SilkS")
			(effects
				(font
					(size 0.65 0.65)
					(thickness 0.15)
				)
				(justify left bottom)
			)
		)
		(property "Value" "R_10k_0603"
			(at 0 1.6 90)
			(layer "F.Fab")
			(hide yes)
			(effects
				(font
					(size 0.7 0.7)
					(thickness 0.15)
				)
				(justify left bottom)
			)
		)
		(property "Datasheet" "https://www.bourns.com/docs/product-datasheets/cr.pdf"
			(at 0 0 90)
			(layer "F.Fab")
			(hide yes)
			(effects
				(font
					(size 1.27 1.27)
					(thickness 0.15)
				)
			)
		)
		(property "Description" "SMD Chip Resistor, 10 kohm, ± 1%, 100 mW, 0603 [1608 Metric], Thick Film, General Purpose"
			(at 0 0 90)
			(layer "F.Fab")
			(hide yes)
			(effects
				(font
					(size 1.27 1.27)
					(thickness 0.15)
				)
			)
		)
		(property "Author" "Antmicro"
			(at 247.18 -69.88 0)
			(layer "F.Fab")
			(hide yes)
			(effects
				(font
					(size 1 1)
					(thickness 0.15)
				)
			)
		)
		(property "License" "Apache-2.0"
			(at 247.18 -69.88 0)
			(layer "F.Fab")
			(hide yes)
			(effects
				(font
					(size 1 1)
					(thickness 0.15)
				)
			)
		)
		(property "MPN" "CR0603-FX-1002ELF"
			(at 247.18 -69.88 0)
			(layer "F.Fab")
			(hide yes)
			(effects
				(font
					(size 1 1)
					(thickness 0.15)
				)
			)
		)
		(property "Manufacturer" "Bourns"
			(at 247.18 -69.88 0)
			(layer "F.Fab")
			(hide yes)
			(effects
				(font
					(size 1 1)
					(thickness 0.15)
				)
			)
		)
		(property "Tolerance" "1%"
			(at 247.18 -69.88 0)
			(layer "F.Fab")
			(hide yes)
			(effects
				(font
					(size 1 1)
					(thickness 0.15)
				)
			)
		)
		(property "Val" "10k"
			(at 247.18 -69.88 0)
			(layer "F.Fab")
			(hide yes)
			(effects
				(font
					(size 1 1)
					(thickness 0.15)
				)
			)
		)
		(sheetname "/Peripherals/")
		(sheetfile "peripherals.kicad_sch")
		(attr smd)
		(fp_line
			(start -0.15 -0.4)
			(end 0.15 -0.4)
			(stroke
				(width 0.15)
				(type solid)
			)
			(layer "F.SilkS")
		)
		(fp_line
			(start -0.15 0.4)
			(end 0.15 0.4)
			(stroke
				(width 0.15)
				(type solid)
			)
			(layer "F.SilkS")
		)
		(fp_rect
			(start -1.25 -0.65)
			(end 1.25 0.65)
			(stroke
				(width 0.05)
				(type solid)
			)
			(fill no)
			(layer "F.CrtYd")
		)
		(fp_rect
			(start -0.8 -0.4)
			(end 0.8 0.4)
			(stroke
				(width 0.15)
				(type solid)
			)
			(fill no)
			(layer "F.Fab")
		)
		(fp_text user "${REFERENCE}"
			(at -1.25 3.898 90)
			(layer "F.Fab")
			(effects
				(font
					(size 0.7 0.7)
					(thickness 0.15)
				)
				(justify left bottom)
			)
		)
		(fp_text user "Author: Antmicro"
			(at -1.25 4.9 90)
			(layer "F.Fab")
			(effects
				(font
					(size 0.7 0.7)
					(thickness 0.15)
				)
				(justify left bottom)
			)
		)
		(fp_text user "License: Apache-2.0"
			(at -1.25 5.9 90)
			(layer "F.Fab")
			(effects
				(font
					(size 0.7 0.7)
					(thickness 0.15)
				)
				(justify left bottom)
			)
		)
		(pad "1" smd roundrect
			(at -0.7 0 90)
			(size 0.8 1)
			(layers "F.Cu" "F.Mask" "F.Paste")
			(roundrect_rratio 0.2)
			(net 2 "+3V3")
			(pintype "passive")
		)
		(pad "2" smd roundrect
			(at 0.7 0 90)
			(size 0.8 1)
			(layers "F.Cu" "F.Mask" "F.Paste")
			(roundrect_rratio 0.2)
			(net 307 "/Peripherals/FFC1_PEN")
			(pintype "passive")
		)
	)
	(footprint "antmicro-footprints:R_0603_1608Metric"
		(layer "F.Cu")
		(at 162.83 116.35 90)
		(descr "Resistor SMD 0603")
		(tags "resistor SMD 0603")
		(property "Reference" "R112"
			(at 1.21 0.4 90)
			(layer "F.SilkS")
			(effects
				(font
					(size 0.65 0.65)
					(thickness 0.15)
				)
				(justify left bottom)
			)
		)
		(property "Value" "R_200R_0603"
			(at 0 1.6 90)
			(layer "F.Fab")
			(hide yes)
			(effects
				(font
					(size 0.7 0.7)
					(thickness 0.15)
				)
				(justify left bottom)
			)
		)
		(property "Datasheet" "https://www.bourns.com/docs/product-datasheets/cr.pdf"
			(at 0 0 90)
			(layer "F.Fab")
			(hide yes)
			(effects
				(font
					(size 1.27 1.27)
					(thickness 0.15)
				)
			)
		)
		(property "Description" "SMD Chip Resistor, 200 ohm, ± 1%, 100 mW, 0603 [1608 Metric], Thick Film, General Purpose"
			(at 0 0 90)
			(layer "F.Fab")
			(hide yes)
			(effects
				(font
					(size 1.27 1.27)
					(thickness 0.15)
				)
			)
		)
		(property "Author" "Antmicro"
			(at 279.18 -46.48 0)
			(layer "F.Fab")
			(hide yes)
			(effects
				(font
					(size 1 1)
					(thickness 0.15)
				)
			)
		)
		(property "License" "Apache-2.0"
			(at 279.18 -46.48 0)
			(layer "F.Fab")
			(hide yes)
			(effects
				(font
					(size 1 1)
					(thickness 0.15)
				)
			)
		)
		(property "MPN" "CR0603-FX-2000ELF"
			(at 279.18 -46.48 0)
			(layer "F.Fab")
			(hide yes)
			(effects
				(font
					(size 1 1)
					(thickness 0.15)
				)
			)
		)
		(property "Manufacturer" "Bourns"
			(at 279.18 -46.48 0)
			(layer "F.Fab")
			(hide yes)
			(effects
				(font
					(size 1 1)
					(thickness 0.15)
				)
			)
		)
		(property "Tolerance" "1%"
			(at 279.18 -46.48 0)
			(layer "F.Fab")
			(hide yes)
			(effects
				(font
					(size 1 1)
					(thickness 0.15)
				)
			)
		)
		(property "Val" "200R"
			(at 279.18 -46.48 0)
			(layer "F.Fab")
			(hide yes)
			(effects
				(font
					(size 1 1)
					(thickness 0.15)
				)
			)
		)
		(sheetname "/Peripherals/")
		(sheetfile "peripherals.kicad_sch")
		(attr smd)
		(fp_line
			(start -0.15 -0.4)
			(end 0.15 -0.4)
			(stroke
				(width 0.15)
				(type solid)
			)
			(layer "F.SilkS")
		)
		(fp_line
			(start -0.15 0.4)
			(end 0.15 0.4)
			(stroke
				(width 0.15)
				(type solid)
			)
			(layer "F.SilkS")
		)
		(fp_rect
			(start -1.25 -0.65)
			(end 1.25 0.65)
			(stroke
				(width 0.05)
				(type solid)
			)
			(fill no)
			(layer "F.CrtYd")
		)
		(fp_rect
			(start -0.8 -0.4)
			(end 0.8 0.4)
			(stroke
				(width 0.15)
				(type solid)
			)
			(fill no)
			(layer "F.Fab")
		)
		(fp_text user "${REFERENCE}"
			(at -1.25 3.898 90)
			(layer "F.Fab")
			(effects
				(font
					(size 0.7 0.7)
					(thickness 0.15)
				)
				(justify left bottom)
			)
		)
		(fp_text user "Author: Antmicro"
			(at -1.25 4.9 90)
			(layer "F.Fab")
			(effects
				(font
					(size 0.7 0.7)
					(thickness 0.15)
				)
				(justify left bottom)
			)
		)
		(fp_text user "License: Apache-2.0"
			(at -1.25 5.9 90)
			(layer "F.Fab")
			(effects
				(font
					(size 0.7 0.7)
					(thickness 0.15)
				)
				(justify left bottom)
			)
		)
		(pad "1" smd roundrect
			(at -0.7 0 90)
			(size 0.8 1)
			(layers "F.Cu" "F.Mask" "F.Paste")
			(roundrect_rratio 0.2)
			(net 64 "Net-(D4-A)")
			(pintype "passive")
		)
		(pad "2" smd roundrect
			(at 0.7 0 90)
			(size 0.8 1)
			(layers "F.Cu" "F.Mask" "F.Paste")
			(roundrect_rratio 0.2)
			(net 35 "LED0")
			(pintype "passive")
		)
	)
)
